(kicad_pcb
	(version 20260206)
	(generator "pcbnew")
	(generator_version "10.0")
	(general
		(thickness 1.6)
		(legacy_teardrops no)
	)
	(paper "A4")
	(title_block
		(title "01162023_DA0F0TEBIF0_F0T_Expander_BD_F_brd_V02_OCP.brd")
		(comment 1 "Grand Teton / footprints 4536-4543 of 9728")
	)
	(layers
		(0 "F.Cu" signal "TOP")
		(4 "In1.Cu" signal "GND")
		(6 "In2.Cu" signal "VCC")
		(8 "In3.Cu" signal "VCC1")
		(10 "In4.Cu" signal "GND1")
		(12 "In5.Cu" signal "IN1")
		(14 "In6.Cu" signal "GND2")
		(16 "In7.Cu" signal "IN2")
		(18 "In8.Cu" signal "GND3")
		(20 "In9.Cu" signal "IN3")
		(22 "In10.Cu" signal "GND4")
		(24 "In11.Cu" signal "IN4")
		(26 "In12.Cu" signal "GND5")
		(28 "In13.Cu" signal "IN5")
		(30 "In14.Cu" signal "GND6")
		(32 "In15.Cu" signal "IN6")
		(34 "In16.Cu" signal "GND7")
		(2 "B.Cu" signal "BOTTOM")
		(9 "F.Adhes" user "F.Adhesive")
		(11 "B.Adhes" user "B.Adhesive")
		(13 "F.Paste" user "Package Geometry/Pastemask Top")
		(15 "B.Paste" user "Package Geometry/Pastemask Bottom")
		(5 "F.SilkS" user "Ref Des/Silkscreen Top")
		(7 "B.SilkS" user "Ref Des/Silkscreen Bottom")
		(1 "F.Mask" user "Board Geometry/Soldermask Top")
		(3 "B.Mask" user "Board Geometry/Soldermask Bottom")
		(17 "Dwgs.User" user "User.Drawings")
		(19 "Cmts.User" user "User.Comments")
		(21 "Eco1.User" user "User.Eco1")
		(23 "Eco2.User" user "User.Eco2")
		(25 "Edge.Cuts" user "Board Geometry/Outline")
		(27 "Margin" user)
		(31 "F.CrtYd" user "Package Geometry/Place Bound Top")
		(29 "B.CrtYd" user "Package Geometry/Place Bound Bottom")
		(35 "F.Fab" user "Ref Des/Assembly Top")
		(33 "B.Fab" user "Ref Des/Assembly Bottom")
	)
	(footprint ""
		(layer "F.Cu")
		(at 362.339382 -239.62106)
		(property "Reference" "R6410"
			(at 0 0 0)
			(layer "F.SilkS")
			(hide yes)
			(effects
				(font
					(size 1.27 1.27)
				)
			)
		)
		(property "Value" ""
			(at 0 0 0)
			(layer "F.Fab")
			(effects
				(font
					(size 1.27 1.27)
				)
			)
		)
		(duplicate_pad_numbers_are_jumpers no)
		(fp_line
			(start -0.7874 -0.4064)
			(end 0.7874 -0.4064)
			(stroke
				(width 0.1524)
				(type default)
			)
			(layer "F.SilkS")
		)
		(fp_line
			(start -0.7874 0.4064)
			(end -0.7874 -0.4064)
			(stroke
				(width 0.1524)
				(type default)
			)
			(layer "F.SilkS")
		)
		(fp_line
			(start 0.7874 -0.4064)
			(end 0.7874 0.4064)
			(stroke
				(width 0.1524)
				(type default)
			)
			(layer "F.SilkS")
		)
		(fp_line
			(start 0.7874 0.4064)
			(end -0.7874 0.4064)
			(stroke
				(width 0.1524)
				(type default)
			)
			(layer "F.SilkS")
		)
		(fp_line
			(start -0.67945 -0.305054)
			(end -0.12065 -0.305054)
			(stroke
				(width 0.1)
				(type default)
			)
			(layer "F.Fab")
		)
		(fp_line
			(start -0.67945 0.3048)
			(end -0.67945 -0.305054)
			(stroke
				(width 0.1)
				(type default)
			)
			(layer "F.Fab")
		)
		(fp_line
			(start -0.12065 -0.305054)
			(end -0.12065 -0.2794)
			(stroke
				(width 0.1)
				(type default)
			)
			(layer "F.Fab")
		)
		(fp_line
			(start -0.12065 -0.2794)
			(end 0.12065 -0.2794)
			(stroke
				(width 0.1)
				(type default)
			)
			(layer "F.Fab")
		)
		(fp_line
			(start -0.12065 0.2794)
			(end -0.12065 0.3048)
			(stroke
				(width 0.1)
				(type default)
			)
			(layer "F.Fab")
		)
		(fp_line
			(start -0.12065 0.3048)
			(end -0.67945 0.3048)
			(stroke
				(width 0.1)
				(type default)
			)
			(layer "F.Fab")
		)
		(fp_line
			(start 0.120396 0.2794)
			(end -0.12065 0.2794)
			(stroke
				(width 0.1)
				(type default)
			)
			(layer "F.Fab")
		)
		(fp_line
			(start 0.120396 0.3048)
			(end 0.120396 0.2794)
			(stroke
				(width 0.1)
				(type default)
			)
			(layer "F.Fab")
		)
		(fp_line
			(start 0.12065 -0.3048)
			(end 0.67945 -0.3048)
			(stroke
				(width 0.1)
				(type default)
			)
			(layer "F.Fab")
		)
		(fp_line
			(start 0.12065 -0.2794)
			(end 0.12065 -0.3048)
			(stroke
				(width 0.1)
				(type default)
			)
			(layer "F.Fab")
		)
		(fp_line
			(start 0.67945 -0.3048)
			(end 0.67945 0.3048)
			(stroke
				(width 0.1)
				(type default)
			)
			(layer "F.Fab")
		)
		(fp_line
			(start 0.67945 0.3048)
			(end 0.120396 0.3048)
			(stroke
				(width 0.1)
				(type default)
			)
			(layer "F.Fab")
		)
		(pad "1" smd circle
			(at -0.40005 0)
			(size 0 0)
			(layers "F.Cu" "F.Mask" "F.Paste")
			(net "GND")
		)
		(pad "2" smd circle
			(at 0.40005 0)
			(size 0 0)
			(layers "F.Cu" "F.Mask" "F.Paste")
			(net "PWRGD_P3V3_AUX_BUF")
		)
	)
	(footprint ""
		(layer "F.Cu")
		(at 337.349084 -343.952322 90)
		(property "Reference" "C573"
			(at 0 0 90)
			(layer "F.SilkS")
			(hide yes)
			(effects
				(font
					(size 1.27 1.27)
				)
			)
		)
		(property "Value" ""
			(at 0 0 90)
			(layer "F.Fab")
			(effects
				(font
					(size 1.27 1.27)
				)
			)
		)
		(duplicate_pad_numbers_are_jumpers no)
		(fp_line
			(start 0.299974 -0.150114)
			(end 0.299974 0.150114)
			(stroke
				(width 0.1)
				(type default)
			)
			(layer "F.Fab")
		)
		(fp_line
			(start -0.299974 -0.150114)
			(end 0.299974 -0.150114)
			(stroke
				(width 0.1)
				(type default)
			)
			(layer "F.Fab")
		)
		(fp_line
			(start 0.299974 0.150114)
			(end -0.299974 0.150114)
			(stroke
				(width 0.1)
				(type default)
			)
			(layer "F.Fab")
		)
		(fp_line
			(start -0.299974 0.150114)
			(end -0.299974 -0.150114)
			(stroke
				(width 0.1)
				(type default)
			)
			(layer "F.Fab")
		)
		(pad "1" smd rect
			(at -0.2667 0 90)
			(size 0.3048 0.381)
			(layers "F.Cu" "F.Mask" "F.Paste")
			(net "P5E_PEX2_STN6_TX_DP<100>")
		)
		(pad "2" smd rect
			(at 0.2667 0 90)
			(size 0.3048 0.381)
			(layers "F.Cu" "F.Mask" "F.Paste")
			(net "P5E_PEX2_STN6_TX_C_DP<100>")
		)
	)
	(footprint ""
		(layer "F.Cu")
		(at 142.368016 -51.019456)
		(property "Reference" "PC363"
			(at 0 0 0)
			(layer "F.SilkS")
			(hide yes)
			(effects
				(font
					(size 1.27 1.27)
				)
			)
		)
		(property "Value" ""
			(at 0 0 0)
			(layer "F.Fab")
			(effects
				(font
					(size 1.27 1.27)
				)
			)
		)
		(duplicate_pad_numbers_are_jumpers no)
		(fp_line
			(start -0.7874 -0.4064)
			(end 0.7874 -0.4064)
			(stroke
				(width 0.1524)
				(type default)
			)
			(layer "F.SilkS")
		)
		(fp_line
			(start -0.7874 0.4064)
			(end -0.7874 -0.4064)
			(stroke
				(width 0.1524)
				(type default)
			)
			(layer "F.SilkS")
		)
		(fp_line
			(start 0.7874 -0.4064)
			(end 0.7874 0.4064)
			(stroke
				(width 0.1524)
				(type default)
			)
			(layer "F.SilkS")
		)
		(fp_line
			(start 0.7874 0.4064)
			(end -0.7874 0.4064)
			(stroke
				(width 0.1524)
				(type default)
			)
			(layer "F.SilkS")
		)
		(fp_line
			(start -0.6858 -0.3048)
			(end -0.1016 -0.3048)
			(stroke
				(width 0.1)
				(type default)
			)
			(layer "F.Fab")
		)
		(fp_line
			(start -0.6858 0.3048)
			(end -0.6858 -0.3048)
			(stroke
				(width 0.1)
				(type default)
			)
			(layer "F.Fab")
		)
		(fp_line
			(start -0.1016 -0.3048)
			(end -0.1016 -0.2794)
			(stroke
				(width 0.1)
				(type default)
			)
			(layer "F.Fab")
		)
		(fp_line
			(start -0.1016 -0.2794)
			(end 0.1016 -0.2794)
			(stroke
				(width 0.1)
				(type default)
			)
			(layer "F.Fab")
		)
		(fp_line
			(start -0.1016 0.2794)
			(end -0.1016 0.3048)
			(stroke
				(width 0.1)
				(type default)
			)
			(layer "F.Fab")
		)
		(fp_line
			(start -0.1016 0.3048)
			(end -0.6858 0.3048)
			(stroke
				(width 0.1)
				(type default)
			)
			(layer "F.Fab")
		)
		(fp_line
			(start 0.1016 -0.3048)
			(end 0.6858 -0.3048)
			(stroke
				(width 0.1)
				(type default)
			)
			(layer "F.Fab")
		)
		(fp_line
			(start 0.1016 -0.2794)
			(end 0.1016 -0.3048)
			(stroke
				(width 0.1)
				(type default)
			)
			(layer "F.Fab")
		)
		(fp_line
			(start 0.1016 0.2794)
			(end -0.1016 0.2794)
			(stroke
				(width 0.1)
				(type default)
			)
			(layer "F.Fab")
		)
		(fp_line
			(start 0.1016 0.3048)
			(end 0.1016 0.2794)
			(stroke
				(width 0.1)
				(type default)
			)
			(layer "F.Fab")
		)
		(fp_line
			(start 0.6858 -0.3048)
			(end 0.6858 0.3048)
			(stroke
				(width 0.1)
				(type default)
			)
			(layer "F.Fab")
		)
		(fp_line
			(start 0.6858 0.3048)
			(end 0.1016 0.3048)
			(stroke
				(width 0.1)
				(type default)
			)
			(layer "F.Fab")
		)
		(pad "1" smd rect
			(at -0.40005 0 180)
			(size 0.4572 0.508)
			(layers "F.Cu" "F.Mask" "F.Paste")
			(net "P12V_SSD4_SS")
		)
		(pad "2" smd rect
			(at 0.40005 0 180)
			(size 0.4572 0.508)
			(layers "F.Cu" "F.Mask" "F.Paste")
			(net "GND")
		)
	)
	(footprint ""
		(layer "F.Cu")
		(at 77.353922 -83.932268 90)
		(property "Reference" "C872"
			(at 0 0 90)
			(layer "F.SilkS")
			(hide yes)
			(effects
				(font
					(size 1.27 1.27)
				)
			)
		)
		(property "Value" ""
			(at 0 0 90)
			(layer "F.Fab")
			(effects
				(font
					(size 1.27 1.27)
				)
			)
		)
		(duplicate_pad_numbers_are_jumpers no)
		(fp_line
			(start 0.7874 -0.4064)
			(end 0.7874 0.4064)
			(stroke
				(width 0.1524)
				(type default)
			)
			(layer "F.SilkS")
		)
		(fp_line
			(start -0.7874 -0.4064)
			(end 0.7874 -0.4064)
			(stroke
				(width 0.1524)
				(type default)
			)
			(layer "F.SilkS")
		)
		(fp_line
			(start 0.7874 0.4064)
			(end -0.7874 0.4064)
			(stroke
				(width 0.1524)
				(type default)
			)
			(layer "F.SilkS")
		)
		(fp_line
			(start -0.7874 0.4064)
			(end -0.7874 -0.4064)
			(stroke
				(width 0.1524)
				(type default)
			)
			(layer "F.SilkS")
		)
		(fp_line
			(start -0.12065 -0.305054)
			(end -0.12065 -0.2794)
			(stroke
				(width 0.1)
				(type default)
			)
			(layer "F.Fab")
		)
		(fp_line
			(start -0.67945 -0.305054)
			(end -0.12065 -0.305054)
			(stroke
				(width 0.1)
				(type default)
			)
			(layer "F.Fab")
		)
		(fp_line
			(start 0.67945 -0.3048)
			(end 0.67945 0.3048)
			(stroke
				(width 0.1)
				(type default)
			)
			(layer "F.Fab")
		)
		(fp_line
			(start 0.12065 -0.3048)
			(end 0.67945 -0.3048)
			(stroke
				(width 0.1)
				(type default)
			)
			(layer "F.Fab")
		)
		(fp_line
			(start 0.12065 -0.2794)
			(end 0.12065 -0.3048)
			(stroke
				(width 0.1)
				(type default)
			)
			(layer "F.Fab")
		)
		(fp_line
			(start -0.12065 -0.2794)
			(end 0.12065 -0.2794)
			(stroke
				(width 0.1)
				(type default)
			)
			(layer "F.Fab")
		)
		(fp_line
			(start 0.120396 0.2794)
			(end -0.12065 0.2794)
			(stroke
				(width 0.1)
				(type default)
			)
			(layer "F.Fab")
		)
		(fp_line
			(start -0.12065 0.2794)
			(end -0.12065 0.3048)
			(stroke
				(width 0.1)
				(type default)
			)
			(layer "F.Fab")
		)
		(fp_line
			(start 0.67945 0.3048)
			(end 0.120396 0.3048)
			(stroke
				(width 0.1)
				(type default)
			)
			(layer "F.Fab")
		)
		(fp_line
			(start 0.120396 0.3048)
			(end 0.120396 0.2794)
			(stroke
				(width 0.1)
				(type default)
			)
			(layer "F.Fab")
		)
		(fp_line
			(start -0.12065 0.3048)
			(end -0.67945 0.3048)
			(stroke
				(width 0.1)
				(type default)
			)
			(layer "F.Fab")
		)
		(fp_line
			(start -0.67945 0.3048)
			(end -0.67945 -0.305054)
			(stroke
				(width 0.1)
				(type default)
			)
			(layer "F.Fab")
		)
		(pad "1" smd circle
			(at -0.40005 0 90)
			(size 0 0)
			(layers "F.Cu" "F.Mask" "F.Paste")
			(net "P3V3_AUX")
		)
		(pad "2" smd circle
			(at 0.40005 0 90)
			(size 0 0)
			(layers "F.Cu" "F.Mask" "F.Paste")
			(net "GND")
		)
	)
	(footprint ""
		(layer "F.Cu")
		(at 84.023962 -350.098614 90)
		(property "Reference" "C150"
			(at 0 0 90)
			(layer "F.SilkS")
			(hide yes)
			(effects
				(font
					(size 1.27 1.27)
				)
			)
		)
		(property "Value" ""
			(at 0 0 90)
			(layer "F.Fab")
			(effects
				(font
					(size 1.27 1.27)
				)
			)
		)
		(duplicate_pad_numbers_are_jumpers no)
		(fp_line
			(start 0.299974 -0.150114)
			(end 0.299974 0.150114)
			(stroke
				(width 0.1)
				(type default)
			)
			(layer "F.Fab")
		)
		(fp_line
			(start -0.299974 -0.150114)
			(end 0.299974 -0.150114)
			(stroke
				(width 0.1)
				(type default)
			)
			(layer "F.Fab")
		)
		(fp_line
			(start 0.299974 0.150114)
			(end -0.299974 0.150114)
			(stroke
				(width 0.1)
				(type default)
			)
			(layer "F.Fab")
		)
		(fp_line
			(start -0.299974 0.150114)
			(end -0.299974 -0.150114)
			(stroke
				(width 0.1)
				(type default)
			)
			(layer "F.Fab")
		)
		(pad "1" smd rect
			(at -0.2667 0 90)
			(size 0.3048 0.381)
			(layers "F.Cu" "F.Mask" "F.Paste")
			(net "P5E_PEX0_STN6_TX_DN<101>")
		)
		(pad "2" smd rect
			(at 0.2667 0 90)
			(size 0.3048 0.381)
			(layers "F.Cu" "F.Mask" "F.Paste")
			(net "P5E_PEX0_STN6_TX_C_DN<101>")
		)
	)
	(footprint ""
		(layer "F.Cu")
		(at 33.486344 -250.070874 -90)
		(property "Reference" "R1119"
			(at 0 0 270)
			(layer "F.SilkS")
			(hide yes)
			(effects
				(font
					(size 1.27 1.27)
				)
			)
		)
		(property "Value" ""
			(at 0 0 270)
			(layer "F.Fab")
			(effects
				(font
					(size 1.27 1.27)
				)
			)
		)
		(duplicate_pad_numbers_are_jumpers no)
		(fp_line
			(start -0.7874 0.4064)
			(end -0.7874 -0.4064)
			(stroke
				(width 0.1524)
				(type default)
			)
			(layer "F.SilkS")
		)
		(fp_line
			(start 0.7874 0.4064)
			(end -0.7874 0.4064)
			(stroke
				(width 0.1524)
				(type default)
			)
			(layer "F.SilkS")
		)
		(fp_line
			(start -0.7874 -0.4064)
			(end 0.7874 -0.4064)
			(stroke
				(width 0.1524)
				(type default)
			)
			(layer "F.SilkS")
		)
		(fp_line
			(start 0.7874 -0.4064)
			(end 0.7874 0.4064)
			(stroke
				(width 0.1524)
				(type default)
			)
			(layer "F.SilkS")
		)
		(fp_line
			(start -0.67945 0.3048)
			(end -0.67945 -0.305054)
			(stroke
				(width 0.1)
				(type default)
			)
			(layer "F.Fab")
		)
		(fp_line
			(start -0.12065 0.3048)
			(end -0.67945 0.3048)
			(stroke
				(width 0.1)
				(type default)
			)
			(layer "F.Fab")
		)
		(fp_line
			(start 0.120396 0.3048)
			(end 0.120396 0.2794)
			(stroke
				(width 0.1)
				(type default)
			)
			(layer "F.Fab")
		)
		(fp_line
			(start 0.67945 0.3048)
			(end 0.120396 0.3048)
			(stroke
				(width 0.1)
				(type default)
			)
			(layer "F.Fab")
		)
		(fp_line
			(start -0.12065 0.2794)
			(end -0.12065 0.3048)
			(stroke
				(width 0.1)
				(type default)
			)
			(layer "F.Fab")
		)
		(fp_line
			(start 0.120396 0.2794)
			(end -0.12065 0.2794)
			(stroke
				(width 0.1)
				(type default)
			)
			(layer "F.Fab")
		)
		(fp_line
			(start -0.12065 -0.2794)
			(end 0.12065 -0.2794)
			(stroke
				(width 0.1)
				(type default)
			)
			(layer "F.Fab")
		)
		(fp_line
			(start 0.12065 -0.2794)
			(end 0.12065 -0.3048)
			(stroke
				(width 0.1)
				(type default)
			)
			(layer "F.Fab")
		)
		(fp_line
			(start 0.12065 -0.3048)
			(end 0.67945 -0.3048)
			(stroke
				(width 0.1)
				(type default)
			)
			(layer "F.Fab")
		)
		(fp_line
			(start 0.67945 -0.3048)
			(end 0.67945 0.3048)
			(stroke
				(width 0.1)
				(type default)
			)
			(layer "F.Fab")
		)
		(fp_line
			(start -0.67945 -0.305054)
			(end -0.12065 -0.305054)
			(stroke
				(width 0.1)
				(type default)
			)
			(layer "F.Fab")
		)
		(fp_line
			(start -0.12065 -0.305054)
			(end -0.12065 -0.2794)
			(stroke
				(width 0.1)
				(type default)
			)
			(layer "F.Fab")
		)
		(pad "1" smd circle
			(at -0.40005 0 270)
			(size 0 0)
			(layers "F.Cu" "F.Mask" "F.Paste")
			(net "PEX0_DBG_MODE2")
		)
		(pad "2" smd circle
			(at 0.40005 0 270)
			(size 0 0)
			(layers "F.Cu" "F.Mask" "F.Paste")
			(net "P1V8_PEX")
		)
	)
	(footprint ""
		(layer "F.Cu")
		(at 246.85371 -162.003994 -90)
		(property "Reference" "R954"
			(at 0 0 270)
			(layer "F.SilkS")
			(hide yes)
			(effects
				(font
					(size 1.27 1.27)
				)
			)
		)
		(property "Value" ""
			(at 0 0 270)
			(layer "F.Fab")
			(effects
				(font
					(size 1.27 1.27)
				)
			)
		)
		(duplicate_pad_numbers_are_jumpers no)
		(fp_line
			(start -0.7874 0.4064)
			(end -0.7874 -0.4064)
			(stroke
				(width 0.1524)
				(type default)
			)
			(layer "F.SilkS")
		)
		(fp_line
			(start 0.7874 0.4064)
			(end -0.7874 0.4064)
			(stroke
				(width 0.1524)
				(type default)
			)
			(layer "F.SilkS")
		)
		(fp_line
			(start -0.7874 -0.4064)
			(end 0.7874 -0.4064)
			(stroke
				(width 0.1524)
				(type default)
			)
			(layer "F.SilkS")
		)
		(fp_line
			(start 0.7874 -0.4064)
			(end 0.7874 0.4064)
			(stroke
				(width 0.1524)
				(type default)
			)
			(layer "F.SilkS")
		)
		(fp_line
			(start -0.67945 0.3048)
			(end -0.67945 -0.305054)
			(stroke
				(width 0.1)
				(type default)
			)
			(layer "F.Fab")
		)
		(fp_line
			(start -0.12065 0.3048)
			(end -0.67945 0.3048)
			(stroke
				(width 0.1)
				(type default)
			)
			(layer "F.Fab")
		)
		(fp_line
			(start 0.120396 0.3048)
			(end 0.120396 0.2794)
			(stroke
				(width 0.1)
				(type default)
			)
			(layer "F.Fab")
		)
		(fp_line
			(start 0.67945 0.3048)
			(end 0.120396 0.3048)
			(stroke
				(width 0.1)
				(type default)
			)
			(layer "F.Fab")
		)
		(fp_line
			(start -0.12065 0.2794)
			(end -0.12065 0.3048)
			(stroke
				(width 0.1)
				(type default)
			)
			(layer "F.Fab")
		)
		(fp_line
			(start 0.120396 0.2794)
			(end -0.12065 0.2794)
			(stroke
				(width 0.1)
				(type default)
			)
			(layer "F.Fab")
		)
		(fp_line
			(start -0.12065 -0.2794)
			(end 0.12065 -0.2794)
			(stroke
				(width 0.1)
				(type default)
			)
			(layer "F.Fab")
		)
		(fp_line
			(start 0.12065 -0.2794)
			(end 0.12065 -0.3048)
			(stroke
				(width 0.1)
				(type default)
			)
			(layer "F.Fab")
		)
		(fp_line
			(start 0.12065 -0.3048)
			(end 0.67945 -0.3048)
			(stroke
				(width 0.1)
				(type default)
			)
			(layer "F.Fab")
		)
		(fp_line
			(start 0.67945 -0.3048)
			(end 0.67945 0.3048)
			(stroke
				(width 0.1)
				(type default)
			)
			(layer "F.Fab")
		)
		(fp_line
			(start -0.67945 -0.305054)
			(end -0.12065 -0.305054)
			(stroke
				(width 0.1)
				(type default)
			)
			(layer "F.Fab")
		)
		(fp_line
			(start -0.12065 -0.305054)
			(end -0.12065 -0.2794)
			(stroke
				(width 0.1)
				(type default)
			)
			(layer "F.Fab")
		)
		(pad "1" smd circle
			(at -0.40005 0 270)
			(size 0 0)
			(layers "F.Cu" "F.Mask" "F.Paste")
			(net "GND")
		)
		(pad "2" smd circle
			(at 0.40005 0 270)
			(size 0 0)
			(layers "F.Cu" "F.Mask" "F.Paste")
			(net "P12V_NIC4_CO_EN")
		)
	)
	(footprint ""
		(layer "F.Cu")
		(at 72.43445 -33.631886 180)
		(property "Reference" "C82"
			(at 0 0 180)
			(layer "F.SilkS")
			(hide yes)
			(effects
				(font
					(size 1.27 1.27)
				)
			)
		)
		(property "Value" ""
			(at 0 0 180)
			(layer "F.Fab")
			(effects
				(font
					(size 1.27 1.27)
				)
			)
		)
		(duplicate_pad_numbers_are_jumpers no)
		(fp_line
			(start 0.299974 0.150114)
			(end -0.299974 0.150114)
			(stroke
				(width 0.1)
				(type default)
			)
			(layer "F.Fab")
		)
		(fp_line
			(start 0.299974 -0.150114)
			(end 0.299974 0.150114)
			(stroke
				(width 0.1)
				(type default)
			)
			(layer "F.Fab")
		)
		(fp_line
			(start -0.299974 0.150114)
			(end -0.299974 -0.150114)
			(stroke
				(width 0.1)
				(type default)
			)
			(layer "F.Fab")
		)
		(fp_line
			(start -0.299974 -0.150114)
			(end 0.299974 -0.150114)
			(stroke
				(width 0.1)
				(type default)
			)
			(layer "F.Fab")
		)
		(pad "1" smd rect
			(at -0.2667 0 180)
			(size 0.3048 0.381)
			(layers "F.Cu" "F.Mask" "F.Paste")
			(net "P5E_PEX0_STN2_TX_DN<39>")
		)
		(pad "2" smd rect
			(at 0.2667 0 180)
			(size 0.3048 0.381)
			(layers "F.Cu" "F.Mask" "F.Paste")
			(net "P5E_PEX0_STN2_TX_C_DN<39>")
		)
	)
)
